# T6G (Grand Teton) — schematic netlist excerpt (pin names and nets, part order shuffled) for the footprints in the layout excerpt that follows; sources: Cadence DE-HDL packaged netlist, KiCad conversion of 04192023_DAF0TMB3IC0_F0TG_MB_C_brd_V02_OCP.brd

R1167  Q_RES  1K 1% CHIP  pkg 0402LF  page 142 : A = P3V3_AUX ; B = P12V_OCP_V3_2_PLD_PWRGD
H50  HOLE  EMPTY  pkg TH  page 230 : \1\ = GND
R8019  Q_RES  100 1% EMPTY  pkg 0402LF  page 167 : A = P3V3_AUX ; B = FM_JTAG_BMC_R_OE

(kicad_pcb
	(version 20260206)
	(generator "pcbnew")
	(generator_version "10.0")
	(general
		(thickness 1.6)
		(legacy_teardrops no)
	)
	(paper "A4")
	(title_block
		(title "04192023_DAF0TMB3IC0_F0TG_MB_C_brd_V02_OCP.brd")
		(comment 1 "Grand Teton / footprints 368-370 of 8354")
	)
	(layers
		(0 "F.Cu" signal "TOP")
		(4 "In1.Cu" signal "GND")
		(6 "In2.Cu" signal "IN1")
		(8 "In3.Cu" signal "GND1")
		(10 "In4.Cu" signal "IN2")
		(12 "In5.Cu" signal "GND2")
		(14 "In6.Cu" signal "IN3")
		(16 "In7.Cu" signal "GND3")
		(18 "In8.Cu" signal "VCC")
		(20 "In9.Cu" signal "VCC1")
		(22 "In10.Cu" signal "GND4")
		(24 "In11.Cu" signal "IN4")
		(26 "In12.Cu" signal "GND5")
		(28 "In13.Cu" signal "IN5")
		(30 "In14.Cu" signal "GND6")
		(32 "In15.Cu" signal "IN6")
		(34 "In16.Cu" signal "GND7")
		(2 "B.Cu" signal "BOTTOM")
		(9 "F.Adhes" user "F.Adhesive")
		(11 "B.Adhes" user "B.Adhesive")
		(13 "F.Paste" user "Package Geometry/Pastemask Top")
		(15 "B.Paste" user "Package Geometry/Pastemask Bottom")
		(5 "F.SilkS" user "Ref Des/Silkscreen Top")
		(7 "B.SilkS" user "Ref Des/Silkscreen Bottom")
		(1 "F.Mask" user "Board Geometry/Soldermask Top")
		(3 "B.Mask" user "Board Geometry/Soldermask Bottom")
		(17 "Dwgs.User" user "User.Drawings")
		(19 "Cmts.User" user "User.Comments")
		(21 "Eco1.User" user "User.Eco1")
		(23 "Eco2.User" user "User.Eco2")
		(25 "Edge.Cuts" user "Board Geometry/Outline")
		(27 "Margin" user)
		(31 "F.CrtYd" user "Package Geometry/Place Bound Top")
		(29 "B.CrtYd" user "Package Geometry/Place Bound Bottom")
		(35 "F.Fab" user "Ref Des/Assembly Top")
		(33 "B.Fab" user "Ref Des/Assembly Bottom")
	)
	(footprint ""
		(layer "F.Cu")
		(at 422.148 -55.753 90)
		(property "Reference" "R8019"
			(at 0 0 90)
			(layer "F.SilkS")
			(hide yes)
			(effects
				(font
					(size 1.27 1.27)
				)
			)
		)
		(property "Value" ""
			(at 0 0 90)
			(layer "F.Fab")
			(effects
				(font
					(size 1.27 1.27)
				)
			)
		)
		(duplicate_pad_numbers_are_jumpers no)
		(fp_line
			(start 0.7874 -0.4064)
			(end 0.7874 0.4064)
			(stroke
				(width 0.1524)
				(type default)
			)
			(layer "F.SilkS")
		)
		(fp_line
			(start -0.7874 -0.4064)
			(end 0.7874 -0.4064)
			(stroke
				(width 0.1524)
				(type default)
			)
			(layer "F.SilkS")
		)
		(fp_line
			(start 0.7874 0.4064)
			(end -0.7874 0.4064)
			(stroke
				(width 0.1524)
				(type default)
			)
			(layer "F.SilkS")
		)
		(fp_line
			(start -0.7874 0.4064)
			(end -0.7874 -0.4064)
			(stroke
				(width 0.1524)
				(type default)
			)
			(layer "F.SilkS")
		)
		(fp_line
			(start -0.12065 -0.305054)
			(end -0.12065 -0.2794)
			(stroke
				(width 0.1)
				(type default)
			)
			(layer "F.Fab")
		)
		(fp_line
			(start -0.67945 -0.305054)
			(end -0.12065 -0.305054)
			(stroke
				(width 0.1)
				(type default)
			)
			(layer "F.Fab")
		)
		(fp_line
			(start 0.67945 -0.3048)
			(end 0.67945 0.3048)
			(stroke
				(width 0.1)
				(type default)
			)
			(layer "F.Fab")
		)
		(fp_line
			(start 0.12065 -0.3048)
			(end 0.67945 -0.3048)
			(stroke
				(width 0.1)
				(type default)
			)
			(layer "F.Fab")
		)
		(fp_line
			(start 0.12065 -0.2794)
			(end 0.12065 -0.3048)
			(stroke
				(width 0.1)
				(type default)
			)
			(layer "F.Fab")
		)
		(fp_line
			(start -0.12065 -0.2794)
			(end 0.12065 -0.2794)
			(stroke
				(width 0.1)
				(type default)
			)
			(layer "F.Fab")
		)
		(fp_line
			(start 0.120396 0.2794)
			(end -0.12065 0.2794)
			(stroke
				(width 0.1)
				(type default)
			)
			(layer "F.Fab")
		)
		(fp_line
			(start -0.12065 0.2794)
			(end -0.12065 0.3048)
			(stroke
				(width 0.1)
				(type default)
			)
			(layer "F.Fab")
		)
		(fp_line
			(start 0.67945 0.3048)
			(end 0.120396 0.3048)
			(stroke
				(width 0.1)
				(type default)
			)
			(layer "F.Fab")
		)
		(fp_line
			(start 0.120396 0.3048)
			(end 0.120396 0.2794)
			(stroke
				(width 0.1)
				(type default)
			)
			(layer "F.Fab")
		)
		(fp_line
			(start -0.12065 0.3048)
			(end -0.67945 0.3048)
			(stroke
				(width 0.1)
				(type default)
			)
			(layer "F.Fab")
		)
		(fp_line
			(start -0.67945 0.3048)
			(end -0.67945 -0.305054)
			(stroke
				(width 0.1)
				(type default)
			)
			(layer "F.Fab")
		)
		(pad "1" smd circle
			(at -0.40005 0 90)
			(size 0 0)
			(layers "F.Cu" "F.Mask" "F.Paste")
			(net "P3V3_AUX")
		)
		(pad "2" smd circle
			(at 0.40005 0 90)
			(size 0 0)
			(layers "F.Cu" "F.Mask" "F.Paste")
			(net "FM_JTAG_BMC_R_OE")
		)
	)
	(footprint ""
		(layer "F.Cu")
		(at 102.362 -77.216 180)
		(property "Reference" "R1167"
			(at 0 0 180)
			(layer "F.SilkS")
			(hide yes)
			(effects
				(font
					(size 1.27 1.27)
				)
			)
		)
		(property "Value" ""
			(at 0 0 180)
			(layer "F.Fab")
			(effects
				(font
					(size 1.27 1.27)
				)
			)
		)
		(duplicate_pad_numbers_are_jumpers no)
		(fp_line
			(start 0.7874 0.4064)
			(end -0.7874 0.4064)
			(stroke
				(width 0.1524)
				(type default)
			)
			(layer "F.SilkS")
		)
		(fp_line
			(start 0.7874 -0.4064)
			(end 0.7874 0.4064)
			(stroke
				(width 0.1524)
				(type default)
			)
			(layer "F.SilkS")
		)
		(fp_line
			(start -0.7874 0.4064)
			(end -0.7874 -0.4064)
			(stroke
				(width 0.1524)
				(type default)
			)
			(layer "F.SilkS")
		)
		(fp_line
			(start -0.7874 -0.4064)
			(end 0.7874 -0.4064)
			(stroke
				(width 0.1524)
				(type default)
			)
			(layer "F.SilkS")
		)
		(fp_line
			(start 0.67945 0.3048)
			(end 0.120396 0.3048)
			(stroke
				(width 0.1)
				(type default)
			)
			(layer "F.Fab")
		)
		(fp_line
			(start 0.67945 -0.3048)
			(end 0.67945 0.3048)
			(stroke
				(width 0.1)
				(type default)
			)
			(layer "F.Fab")
		)
		(fp_line
			(start 0.12065 -0.2794)
			(end 0.12065 -0.3048)
			(stroke
				(width 0.1)
				(type default)
			)
			(layer "F.Fab")
		)
		(fp_line
			(start 0.12065 -0.3048)
			(end 0.67945 -0.3048)
			(stroke
				(width 0.1)
				(type default)
			)
			(layer "F.Fab")
		)
		(fp_line
			(start 0.120396 0.3048)
			(end 0.120396 0.2794)
			(stroke
				(width 0.1)
				(type default)
			)
			(layer "F.Fab")
		)
		(fp_line
			(start 0.120396 0.2794)
			(end -0.12065 0.2794)
			(stroke
				(width 0.1)
				(type default)
			)
			(layer "F.Fab")
		)
		(fp_line
			(start -0.12065 0.3048)
			(end -0.67945 0.3048)
			(stroke
				(width 0.1)
				(type default)
			)
			(layer "F.Fab")
		)
		(fp_line
			(start -0.12065 0.2794)
			(end -0.12065 0.3048)
			(stroke
				(width 0.1)
				(type default)
			)
			(layer "F.Fab")
		)
		(fp_line
			(start -0.12065 -0.2794)
			(end 0.12065 -0.2794)
			(stroke
				(width 0.1)
				(type default)
			)
			(layer "F.Fab")
		)
		(fp_line
			(start -0.12065 -0.305054)
			(end -0.12065 -0.2794)
			(stroke
				(width 0.1)
				(type default)
			)
			(layer "F.Fab")
		)
		(fp_line
			(start -0.67945 0.3048)
			(end -0.67945 -0.305054)
			(stroke
				(width 0.1)
				(type default)
			)
			(layer "F.Fab")
		)
		(fp_line
			(start -0.67945 -0.305054)
			(end -0.12065 -0.305054)
			(stroke
				(width 0.1)
				(type default)
			)
			(layer "F.Fab")
		)
		(pad "1" smd circle
			(at -0.40005 0 180)
			(size 0 0)
			(layers "F.Cu" "F.Mask" "F.Paste")
			(net "P3V3_AUX")
		)
		(pad "2" smd circle
			(at 0.40005 0 180)
			(size 0 0)
			(layers "F.Cu" "F.Mask" "F.Paste")
			(net "P12V_OCP_V3_2_PLD_PWRGD")
		)
	)
	(footprint ""
		(layer "F.Cu")
		(at 267.45184 -347.8149)
		(property "Reference" "H50"
			(at -1.7526 -4.34213 0)
			(unlocked yes)
			(layer "F.SilkS")
			(effects
				(font
					(size 0.7874 0.5842)
					(thickness 0.1524)
				)
				(justify left)
			)
		)
		(property "Value" ""
			(at 0 0 0)
			(layer "F.Fab")
			(effects
				(font
					(size 1.27 1.27)
				)
			)
		)
		(duplicate_pad_numbers_are_jumpers no)
		(pad "1" thru_hole circle
			(at 0 0)
			(size 6.1976 6.1976)
			(drill 3.7338)
			(layers "*.Cu" "*.Mask")
			(remove_unused_layers no)
			(net "GND")
			(clearance -0.9779)
			(padstack
				(mode front_inner_back)
				(layer "Inner"
					(shape circle)
					(size 5.5372 5.5372)
					(clearance -0.6477)
				)
				(layer "B.Cu"
					(shape circle)
					(size 6.1976 6.1976)
					(clearance -0.9779)
				)
			)
		)
	)
)
